(kicad_pcb
	(version 20260206)
	(generator "pcbnew")
	(generator_version "10.0")
	(general
		(thickness 1.6)
		(legacy_teardrops no)
	)
	(paper "A4")
	(title_block
		(title "v1-tray-backplane — T6M_tray_BP_c_1023_1120.brd")
		(comment 1 "Open CloudServer (Microsoft) / footprints 105-108 of 170")
	)
	(layers
		(0 "F.Cu" signal "TOP")
		(4 "In1.Cu" signal "GND")
		(6 "In2.Cu" signal "IN1")
		(8 "In3.Cu" signal "VCC")
		(10 "In4.Cu" signal "VCC1")
		(12 "In5.Cu" signal "IN2")
		(14 "In6.Cu" signal "GND1")
		(2 "B.Cu" signal "BOTTOM")
		(9 "F.Adhes" user "F.Adhesive")
		(11 "B.Adhes" user "B.Adhesive")
		(13 "F.Paste" user "Package Geometry/Pastemask Top")
		(15 "B.Paste" user "Package Geometry/Pastemask Bottom")
		(5 "F.SilkS" user "Ref Des/Silkscreen Top")
		(7 "B.SilkS" user "Ref Des/Silkscreen Bottom")
		(1 "F.Mask" user "Board Geometry/Soldermask Top")
		(3 "B.Mask" user "Board Geometry/Soldermask Bottom")
		(17 "Dwgs.User" user "User.Drawings")
		(19 "Cmts.User" user "User.Comments")
		(21 "Eco1.User" user "User.Eco1")
		(23 "Eco2.User" user "User.Eco2")
		(25 "Edge.Cuts" user "Board Geometry/Outline")
		(27 "Margin" user)
		(31 "F.CrtYd" user "Package Geometry/Place Bound Top")
		(29 "B.CrtYd" user "Package Geometry/Place Bound Bottom")
		(35 "F.Fab" user "Ref Des/Assembly Top")
		(33 "B.Fab" user "Ref Des/Assembly Bottom")
	)
	(footprint ""
		(layer "F.Cu")
		(at 29.707332 -16.383 90)
		(property "Reference" "R89"
			(at -3.7846 -0.549148 90)
			(unlocked yes)
			(layer "F.SilkS")
			(effects
				(font
					(size 0.7874 0.5842)
					(thickness 0.1524)
				)
				(justify left)
			)
		)
		(property "Value" ""
			(at 0 0 90)
			(layer "F.Fab")
			(effects
				(font
					(size 1.27 1.27)
				)
			)
		)
		(duplicate_pad_numbers_are_jumpers no)
		(fp_line
			(start 0.7874 -0.4064)
			(end 0.7874 0.4064)
			(stroke
				(width 0.1524)
				(type default)
			)
			(layer "F.SilkS")
		)
		(fp_line
			(start -0.7874 -0.4064)
			(end 0.7874 -0.4064)
			(stroke
				(width 0.1524)
				(type default)
			)
			(layer "F.SilkS")
		)
		(fp_line
			(start 0.7874 0.4064)
			(end -0.7874 0.4064)
			(stroke
				(width 0.1524)
				(type default)
			)
			(layer "F.SilkS")
		)
		(fp_line
			(start -0.7874 0.4064)
			(end -0.7874 -0.4064)
			(stroke
				(width 0.1524)
				(type default)
			)
			(layer "F.SilkS")
		)
		(fp_poly
			(pts
				(xy -0.508 0.2794) (xy -0.508 0.2286) (xy -0.635 0.2286) (xy -0.635 -0.254) (xy -0.5334 -0.254)
				(xy -0.5334 -0.2794) (xy 0.5334 -0.2794) (xy 0.5334 -0.254) (xy 0.635 -0.254) (xy 0.635 0.254) (xy 0.5334 0.254)
				(xy 0.5334 0.2794)
			)
			(stroke
				(width 0)
				(type default)
			)
			(fill no)
			(layer "F.CrtYd")
		)
		(pad "1" smd rect
			(at 0.40005 0 90)
			(size 0.4572 0.508)
			(layers "F.Cu" "F.Mask" "F.Paste")
			(net "N39395053")
		)
		(pad "2" smd rect
			(at -0.40005 0 90)
			(size 0.4572 0.508)
			(layers "F.Cu" "F.Mask" "F.Paste")
			(net "GND")
		)
	)
	(footprint ""
		(layer "F.Cu")
		(at 324.358 -2.6416 90)
		(property "Reference" "C32"
			(at -1.651 -5.730748 90)
			(unlocked yes)
			(layer "F.SilkS")
			(effects
				(font
					(size 0.7874 0.5842)
					(thickness 0.1524)
				)
				(justify left)
			)
		)
		(property "Value" ""
			(at 0 0 90)
			(layer "F.Fab")
			(effects
				(font
					(size 1.27 1.27)
				)
			)
		)
		(duplicate_pad_numbers_are_jumpers no)
		(fp_line
			(start 0.7874 -0.4064)
			(end 0.7874 0.4064)
			(stroke
				(width 0.1524)
				(type default)
			)
			(layer "F.SilkS")
		)
		(fp_line
			(start -0.7874 -0.4064)
			(end 0.7874 -0.4064)
			(stroke
				(width 0.1524)
				(type default)
			)
			(layer "F.SilkS")
		)
		(fp_line
			(start 0 0.381)
			(end 0 -0.381)
			(stroke
				(width 0.1524)
				(type default)
			)
			(layer "F.SilkS")
		)
		(fp_line
			(start 0.7874 0.4064)
			(end -0.7874 0.4064)
			(stroke
				(width 0.1524)
				(type default)
			)
			(layer "F.SilkS")
		)
		(fp_line
			(start -0.7874 0.4064)
			(end -0.7874 -0.4064)
			(stroke
				(width 0.1524)
				(type default)
			)
			(layer "F.SilkS")
		)
		(fp_poly
			(pts
				(xy -0.5334 0.254) (xy -0.635 0.254) (xy -0.635 0.2286) (xy -0.635 -0.254) (xy -0.5334 -0.254) (xy -0.5334 -0.2794)
				(xy 0.5334 -0.2794) (xy 0.5334 -0.254) (xy 0.635 -0.254) (xy 0.635 0.254) (xy 0.5334 0.254) (xy 0.5334 0.2794)
				(xy -0.508 0.2794) (xy -0.5334 0.2794)
			)
			(stroke
				(width 0)
				(type default)
			)
			(fill no)
			(layer "F.CrtYd")
		)
		(pad "1" smd rect
			(at 0.40005 0 90)
			(size 0.4572 0.508)
			(layers "F.Cu" "F.Mask" "F.Paste")
			(net "P3V3_10G_4_VCCR")
		)
		(pad "2" smd rect
			(at -0.40005 0 90)
			(size 0.4572 0.508)
			(layers "F.Cu" "F.Mask" "F.Paste")
			(net "GND")
		)
	)
	(footprint ""
		(layer "F.Cu")
		(at 378.431552 -26.227278)
		(property "Reference" "R48"
			(at 33.5026 16.875252 0)
			(unlocked yes)
			(layer "F.SilkS")
			(effects
				(font
					(size 0.7874 0.5842)
					(thickness 0.1524)
				)
				(justify left)
			)
		)
		(property "Value" ""
			(at 0 0 0)
			(layer "F.Fab")
			(effects
				(font
					(size 1.27 1.27)
				)
			)
		)
		(duplicate_pad_numbers_are_jumpers no)
		(fp_line
			(start -0.7874 -0.4064)
			(end 0.7874 -0.4064)
			(stroke
				(width 0.1524)
				(type default)
			)
			(layer "F.SilkS")
		)
		(fp_line
			(start -0.7874 0.4064)
			(end -0.7874 -0.4064)
			(stroke
				(width 0.1524)
				(type default)
			)
			(layer "F.SilkS")
		)
		(fp_line
			(start 0.7874 -0.4064)
			(end 0.7874 0.4064)
			(stroke
				(width 0.1524)
				(type default)
			)
			(layer "F.SilkS")
		)
		(fp_line
			(start 0.7874 0.4064)
			(end -0.7874 0.4064)
			(stroke
				(width 0.1524)
				(type default)
			)
			(layer "F.SilkS")
		)
		(fp_poly
			(pts
				(xy -0.508 0.2794) (xy -0.508 0.2286) (xy -0.635 0.2286) (xy -0.635 -0.254) (xy -0.5334 -0.254)
				(xy -0.5334 -0.2794) (xy 0.5334 -0.2794) (xy 0.5334 -0.254) (xy 0.635 -0.254) (xy 0.635 0.254) (xy 0.5334 0.254)
				(xy 0.5334 0.2794)
			)
			(stroke
				(width 0)
				(type default)
			)
			(fill no)
			(layer "F.CrtYd")
		)
		(pad "1" smd rect
			(at 0.40005 0)
			(size 0.4572 0.508)
			(layers "F.Cu" "F.Mask" "F.Paste")
			(net "GND")
		)
		(pad "2" smd rect
			(at -0.40005 0)
			(size 0.4572 0.508)
			(layers "F.Cu" "F.Mask" "F.Paste")
			(net "ENET10G_3_RS0")
		)
	)
	(footprint ""
		(layer "F.Cu")
		(at 117.31244 -25.45461)
		(property "Reference" "R10"
			(at -61.341 5.115052 0)
			(unlocked yes)
			(layer "F.SilkS")
			(effects
				(font
					(size 0.7874 0.5842)
					(thickness 0.1524)
				)
				(justify left)
			)
		)
		(property "Value" ""
			(at 0 0 0)
			(layer "F.Fab")
			(effects
				(font
					(size 1.27 1.27)
				)
			)
		)
		(duplicate_pad_numbers_are_jumpers no)
		(fp_line
			(start -0.7874 -0.4064)
			(end 0.7874 -0.4064)
			(stroke
				(width 0.1524)
				(type default)
			)
			(layer "F.SilkS")
		)
		(fp_line
			(start -0.7874 0.4064)
			(end -0.7874 -0.4064)
			(stroke
				(width 0.1524)
				(type default)
			)
			(layer "F.SilkS")
		)
		(fp_line
			(start 0.7874 -0.4064)
			(end 0.7874 0.4064)
			(stroke
				(width 0.1524)
				(type default)
			)
			(layer "F.SilkS")
		)
		(fp_line
			(start 0.7874 0.4064)
			(end -0.7874 0.4064)
			(stroke
				(width 0.1524)
				(type default)
			)
			(layer "F.SilkS")
		)
		(fp_poly
			(pts
				(xy -0.508 0.2794) (xy -0.508 0.2286) (xy -0.635 0.2286) (xy -0.635 -0.254) (xy -0.5334 -0.254)
				(xy -0.5334 -0.2794) (xy 0.5334 -0.2794) (xy 0.5334 -0.254) (xy 0.635 -0.254) (xy 0.635 0.254) (xy 0.5334 0.254)
				(xy 0.5334 0.2794)
			)
			(stroke
				(width 0)
				(type default)
			)
			(fill no)
			(layer "F.CrtYd")
		)
		(pad "1" smd rect
			(at 0.40005 0)
			(size 0.4572 0.508)
			(layers "F.Cu" "F.Mask" "F.Paste")
			(net "P3V3_BLAD1")
		)
		(pad "2" smd rect
			(at -0.40005 0)
			(size 0.4572 0.508)
			(layers "F.Cu" "F.Mask" "F.Paste")
			(net "ENET10G_2_MOD_DEF0")
		)
	)
)
